#ISCELL
  mstr_misc dns *
  *
#ISCELL
  pure_quanta quanta_title_block_c *
  *
#CELL
  pure_quanta nct7718w *
  page327_i10
#CELL
  pure_quanta q_res *
  page327_i11
#ISCELL
  logical_power universal_gnd *
  page327_i13
#CELL
  pure_quanta q_res *
  page327_i14
#CELL
  pure_quanta q_res *
  page327_i15
#CELL
  pure_quanta q_res *
  page327_i16
#CELL
  pure_quanta q_res *
  page327_i17
#ISCELL
  logical_power universal_power *
  page327_i18
#ISCELL
  standard offpage *
  page327_i19
#ISCELL
  standard offpage *
  page327_i2
#ISCELL
  standard offpage *
  page327_i20
#ISCELL
  standard offpage *
  page327_i21
#ISCELL
  standard offpage *
  page327_i22
#CELL
  pure_quanta q_res *
  page327_i23
#ISCELL
  logical_power universal_power *
  page327_i24
#CELL
  pure_quanta q_res *
  page327_i25
#CELL
  pure_quanta q_res *
  page327_i26
#ISCELL
  standard offpage *
  page327_i27
#ISCELL
  standard offpage *
  page327_i28
#ISCELL
  standard offpage *
  page327_i29
#ISCELL
  standard offpage *
  page327_i3
#ISCELL
  standard offpage *
  page327_i30
#ISCELL
  standard offpage *
  page327_i31
#ISCELL
  standard offpage *
  page327_i32
#ISCELL
  logical_power universal_gnd *
  page327_i33
#CELL
  pure_quanta sconn21_9193031121lf *
  page327_i34
#ISCELL
  logical_power universal_power *
  page327_i35
#ISCELL
  logical_power universal_gnd *
  page327_i36
#ISCELL
  logical_power universal_gnd *
  page327_i37
#CELL
  pure_quanta q_cap *
  page327_i38
#ISCELL
  standard offpage *
  page327_i39
#CELL
  pure_quanta q_res *
  page327_i4
#ISCELL
  standard offpage *
  page327_i40
#ISCELL
  standard offpage *
  page327_i41
#ISCELL
  standard offpage *
  page327_i42
#ISCELL
  standard offpage *
  page327_i43
#ISCELL
  standard offpage *
  page327_i44
#ISCELL
  standard offpage *
  page327_i45
#ISCELL
  logical_power universal_power *
  page327_i46
#ISCELL
  standard offpage *
  page327_i47
#ISCELL
  logical_power universal_power *
  page327_i48
#CELL
  pure_quanta mmbt3904 *
  page327_i49
#CELL
  pure_quanta q_res *
  page327_i5
#ISCELL
  logical_power gnd *
  page327_i50
#CELL
  pure_quanta conn3_210hp1030br1 *
  page327_i51
#CELL
  pure_quanta q_cap *
  page327_i6
#ISCELL
  logical_power universal_gnd *
  page327_i7
#CELL
  pure_quanta q_cap *
  page327_i8
#ISCELL
  logical_power universal_power *
  page327_i9
